# S9S_MB_2U (Grand Teton) — schematic netlist excerpt (pin names and nets, part order shuffled) for the footprints in the layout excerpt that follows; sources: Cadence DE-HDL packaged netlist, KiCad conversion of 03242023_DA0F0TMBIJ0_F0T_Motherboard_J_brd_V01_OCP.brd

PU44_P0_2  ISL99390FRZTR5935  ISL99390FRZ-TR5935 IC  pkg QFN21_6X5XB  page 275
  VOS  = PVCCINFAON_CPU0_VOS2
  AGND  = GND
  VCC  = PVCCINFAON_CPU0_VDD2
  PVCC  = PVCCFA_EHV_CPU0_PVCC
  PGND1  = GND
  GL1  = NC
  PGND2  = GND
  SW  = SW_PVCCINFAON_CPU0_SW2
  VIN1  = SW_P12V_PVCCINFAON_CPU0_FLT
  VIN2  = SW_P12V_PVCCINFAON_CPU0_FLT
  DNC  = NC
  PHASE  = SW_PVCCINFAON_CPU0_BOOTR2
  BOOT  = SW_PVCCINFAON_CPU0_BOOT2
  PWM  = PVCCINFAON_CPU0_APWM2
  EN  = PVCCINFAON_CPU0_VDD2
  TOUT_FLT  = PVCCINFAON_CPU0_ATSEN
  LSET  = PVCCINFAON_CPU0_LSET2
  IOUT  = PVCCINFAON_CPU0_ACSP2
  REFIN  = PVCCINFAON_CPU0_VREF
  PGND3  = GND
  GL2  = NC

(kicad_pcb
	(version 20260206)
	(generator "pcbnew")
	(generator_version "10.0")
	(general
		(thickness 1.6)
		(legacy_teardrops no)
	)
	(paper "A4")
	(title_block
		(title "03242023_DA0F0TMBIJ0_F0T_Motherboard_J_brd_V01_OCP.brd")
		(comment 1 "Grand Teton / footprints 4024-4024 of 6105")
	)
	(layers
		(0 "F.Cu" signal "TOP")
		(4 "In1.Cu" signal "GND")
		(6 "In2.Cu" signal "IN1")
		(8 "In3.Cu" signal "GND1")
		(10 "In4.Cu" signal "IN2")
		(12 "In5.Cu" signal "GND2")
		(14 "In6.Cu" signal "IN3")
		(16 "In7.Cu" signal "GND3")
		(18 "In8.Cu" signal "VCC")
		(20 "In9.Cu" signal "VCC1")
		(22 "In10.Cu" signal "GND4")
		(24 "In11.Cu" signal "IN4")
		(26 "In12.Cu" signal "GND5")
		(28 "In13.Cu" signal "IN5")
		(30 "In14.Cu" signal "GND6")
		(32 "In15.Cu" signal "IN6")
		(34 "In16.Cu" signal "GND7")
		(2 "B.Cu" signal "BOTTOM")
		(9 "F.Adhes" user "F.Adhesive")
		(11 "B.Adhes" user "B.Adhesive")
		(13 "F.Paste" user "Package Geometry/Pastemask Top")
		(15 "B.Paste" user "Package Geometry/Pastemask Bottom")
		(5 "F.SilkS" user "Ref Des/Silkscreen Top")
		(7 "B.SilkS" user "Ref Des/Silkscreen Bottom")
		(1 "F.Mask" user "Board Geometry/Soldermask Top")
		(3 "B.Mask" user "Board Geometry/Soldermask Bottom")
		(17 "Dwgs.User" user "User.Drawings")
		(19 "Cmts.User" user "User.Comments")
		(21 "Eco1.User" user "User.Eco1")
		(23 "Eco2.User" user "User.Eco2")
		(25 "Edge.Cuts" user "Board Geometry/Outline")
		(27 "Margin" user)
		(31 "F.CrtYd" user "Package Geometry/Place Bound Top")
		(29 "B.CrtYd" user "Package Geometry/Place Bound Bottom")
		(35 "F.Fab" user "Ref Des/Assembly Top")
		(33 "B.Fab" user "Ref Des/Assembly Bottom")
	)
	(footprint ""
		(layer "F.Cu")
		(at 416.009582 -179.457858 -90)
		(property "Reference" "PU44_P0_2"
			(at 4.08051 7.755382 0)
			(unlocked yes)
			(layer "F.SilkS")
			(effects
				(font
					(size 0.7874 0.5842)
					(thickness 0.1524)
				)
				(justify left)
			)
		)
		(property "Value" ""
			(at 0 0 270)
			(layer "F.Fab")
			(effects
				(font
					(size 1.27 1.27)
				)
			)
		)
		(duplicate_pad_numbers_are_jumpers no)
		(fp_line
			(start -2.500122 2.999994)
			(end -2.500122 2.339594)
			(stroke
				(width 0.1524)
				(type default)
			)
			(layer "F.SilkS")
		)
		(fp_line
			(start -2.2987 2.999994)
			(end -2.500122 2.999994)
			(stroke
				(width 0.1524)
				(type default)
			)
			(layer "F.SilkS")
		)
		(fp_line
			(start 2.500122 2.999994)
			(end 2.2987 2.999994)
			(stroke
				(width 0.1524)
				(type default)
			)
			(layer "F.SilkS")
		)
		(fp_line
			(start 2.500122 2.339594)
			(end 2.500122 2.999994)
			(stroke
				(width 0.1524)
				(type default)
			)
			(layer "F.SilkS")
		)
		(fp_line
			(start -2.500122 0.6604)
			(end -2.500122 0.229108)
			(stroke
				(width 0.1524)
				(type default)
			)
			(layer "F.SilkS")
		)
		(fp_line
			(start -2.500122 -2.529078)
			(end -2.500122 -2.999994)
			(stroke
				(width 0.1524)
				(type default)
			)
			(layer "F.SilkS")
		)
		(fp_line
			(start -2.500122 -2.999994)
			(end -2.24409 -2.999994)
			(stroke
				(width 0.1524)
				(type default)
			)
			(layer "F.SilkS")
		)
		(fp_line
			(start 2.31394 -2.999994)
			(end 2.500122 -2.999994)
			(stroke
				(width 0.1524)
				(type default)
			)
			(layer "F.SilkS")
		)
		(fp_line
			(start 2.500122 -2.999994)
			(end 2.500122 -2.44348)
			(stroke
				(width 0.1524)
				(type default)
			)
			(layer "F.SilkS")
		)
		(fp_poly
			(pts
				(xy -4.93395 -2.65811) (xy -4.218432 -2.300478) (xy -4.93395 -1.942846)
			)
			(stroke
				(width 0)
				(type default)
			)
			(fill yes)
			(layer "F.SilkS")
		)
		(fp_line
			(start -2.500122 2.999994)
			(end -2.500122 -2.999994)
			(stroke
				(width 0.1)
				(type default)
			)
			(layer "F.Fab")
		)
		(fp_line
			(start 2.500122 2.999994)
			(end -2.500122 2.999994)
			(stroke
				(width 0.1)
				(type default)
			)
			(layer "F.Fab")
		)
		(fp_line
			(start -2.500122 -2.999994)
			(end 2.500122 -2.999994)
			(stroke
				(width 0.1)
				(type default)
			)
			(layer "F.Fab")
		)
		(fp_line
			(start 2.500122 -2.999994)
			(end 2.500122 2.999994)
			(stroke
				(width 0.1)
				(type default)
			)
			(layer "F.Fab")
		)
		(fp_poly
			(pts
				(xy -4.218432 -2.783078) (xy -4.218432 -1.767078) (xy -3.202432 -2.275078)
			)
			(stroke
				(width 0)
				(type default)
			)
			(fill yes)
			(layer "F.Fab")
		)
		(pad "1" smd rect
			(at -2.400046 -2.275078)
			(size 0.2286 0.6096)
			(layers "F.Cu" "F.Mask" "F.Paste")
			(net "PVCCINFAON_CPU0_VOS2")
		)
		(pad "2" smd rect
			(at -2.400046 -1.82499)
			(size 0.2286 0.6096)
			(layers "F.Cu" "F.Mask" "F.Paste")
			(net "GND")
		)
		(pad "3" smd rect
			(at -2.400046 -1.374902)
			(size 0.2286 0.6096)
			(layers "F.Cu" "F.Mask" "F.Paste")
			(net "PVCCINFAON_CPU0_VDD2")
		)
		(pad "4" smd rect
			(at -2.400046 -0.925068)
			(size 0.2286 0.6096)
			(layers "F.Cu" "F.Mask" "F.Paste")
			(net "PVCCFA_EHV_CPU0_PVCC")
		)
		(pad "5" smd rect
			(at -2.400046 -0.47498)
			(size 0.2286 0.6096)
			(layers "F.Cu" "F.Mask" "F.Paste")
			(net "GND")
		)
		(pad "6" smd rect
			(at -2.400046 -0.024892)
			(size 0.2286 0.6096)
			(layers "F.Cu" "F.Mask" "F.Paste")
			(net "Net_1926")
		)
		(pad "7_9-20_24" smd circle
			(at 0 1.150112)
			(size 0 0)
			(layers "F.Cu" "F.Mask" "F.Paste")
			(net "GND")
		)
		(pad "10_19" smd rect
			(at 0 2.899918)
			(size 0.6096 4.318)
			(layers "F.Cu" "F.Mask" "F.Paste")
			(net "SW_PVCCINFAON_CPU0_SW2")
		)
		(pad "25_29" smd rect
			(at 1.549908 -1.279906 180)
			(size 2.0574 2.3114)
			(layers "F.Cu" "F.Mask" "F.Paste")
			(net "SW_P12V_PVCCINFAON_CPU0_FLT")
		)
		(pad "30" smd rect
			(at 2.05994 -2.899918 270)
			(size 0.2286 0.6096)
			(layers "F.Cu" "F.Mask" "F.Paste")
			(net "SW_P12V_PVCCINFAON_CPU0_FLT")
		)
		(pad "31" smd rect
			(at 1.610106 -2.899918 270)
			(size 0.2286 0.6096)
			(layers "F.Cu" "F.Mask" "F.Paste")
			(net "Net_1925")
		)
		(pad "32" smd rect
			(at 1.160018 -2.899918 270)
			(size 0.2286 0.6096)
			(layers "F.Cu" "F.Mask" "F.Paste")
			(net "SW_PVCCINFAON_CPU0_BOOTR2")
		)
		(pad "33" smd rect
			(at 0.70993 -2.899918 270)
			(size 0.2286 0.6096)
			(layers "F.Cu" "F.Mask" "F.Paste")
			(net "SW_PVCCINFAON_CPU0_BOOT2")
		)
		(pad "34" smd rect
			(at 0.260096 -2.899918 270)
			(size 0.2286 0.6096)
			(layers "F.Cu" "F.Mask" "F.Paste")
			(net "PVCCINFAON_CPU0_APWM2")
		)
		(pad "35" smd rect
			(at -0.189992 -2.899918 270)
			(size 0.2286 0.6096)
			(layers "F.Cu" "F.Mask" "F.Paste")
			(net "PVCCINFAON_CPU0_VDD2")
		)
		(pad "36" smd rect
			(at -0.64008 -2.899918 270)
			(size 0.2286 0.6096)
			(layers "F.Cu" "F.Mask" "F.Paste")
			(net "PVCCINFAON_CPU0_ATSEN")
		)
		(pad "37" smd rect
			(at -1.089914 -2.899918 270)
			(size 0.2286 0.6096)
			(layers "F.Cu" "F.Mask" "F.Paste")
			(net "PVCCINFAON_CPU0_LSET2")
		)
		(pad "38" smd rect
			(at -1.540002 -2.899918 270)
			(size 0.2286 0.6096)
			(layers "F.Cu" "F.Mask" "F.Paste")
			(net "PVCCINFAON_CPU0_ACSP2")
		)
		(pad "39" smd rect
			(at -1.99009 -2.899918 270)
			(size 0.2286 0.6096)
			(layers "F.Cu" "F.Mask" "F.Paste")
			(net "PVCCINFAON_CPU0_VREF")
		)
		(pad "40" smd rect
			(at -0.87503 -1.27508 270)
			(size 1.7526 1.9558)
			(layers "F.Cu" "F.Mask" "F.Paste")
			(net "GND")
		)
		(pad "41" smd rect
			(at -1.525016 0.249936 180)
			(size 0.3048 0.4572)
			(layers "F.Cu" "F.Mask" "F.Paste")
			(net "Net_1927")
		)
		(zone
			(layer "F.Cu")
			(hatch none 0.5)
			(connect_pads
				(clearance 0)
			)
			(min_thickness 0.25)
			(keepout
				(tracks not_allowed)
				(vias allowed)
				(pads allowed)
				(copperpour not_allowed)
				(footprints allowed)
			)
			(placement
				(enabled no)
				(sheetname "")
			)
			(fill
				(thermal_gap 0.5)
				(thermal_bridge_width 0.5)
				(island_removal_mode 0)
			)
			(polygon
				(pts
					(xy 413.009588 -181.95798) (xy 413.540956 -181.95798) (xy 413.758888 -181.740048) (xy 413.758888 -177.168048)
					(xy 413.548576 -176.957736) (xy 413.009588 -176.957736) (xy 413.009588 -177.248058) (xy 413.465264 -177.248058)
					(xy 413.465264 -181.667658) (xy 413.009588 -181.667658)
				)
			)
		)
	)
)
